# T6G (Grand Teton) — schematic netlist excerpt (pin names and nets, part order shuffled) for the footprints in the layout excerpt that follows; sources: Cadence DE-HDL packaged netlist, KiCad conversion of 04192023_DAF0TMB3IC0_F0TG_MB_C_brd_V02_OCP.brd

R3433  Q_RES  4.7K 5% CHIP  pkg 0402LF  page 126 : A = P3V3_AUX ; B = GPU_BASE_HMC_READY_N
R6190  Q_RES  0 5% CHIP  pkg 0201LF  page 180 : A = USB2_CPU0_P0_DP ; B = USB2_CPU0_P0_R1_DP
PR418  Q_RES  49.9 1% CHIP  pkg 0402LF  page 209 : A = GND ; B = PVDD18_S5_P0_RGND

(kicad_pcb
	(version 20260206)
	(generator "pcbnew")
	(generator_version "10.0")
	(general
		(thickness 1.6)
		(legacy_teardrops no)
	)
	(paper "A4")
	(title_block
		(title "04192023_DAF0TMB3IC0_F0TG_MB_C_brd_V02_OCP.brd")
		(comment 1 "Grand Teton / footprints 223-225 of 8354")
	)
	(layers
		(0 "F.Cu" signal "TOP")
		(4 "In1.Cu" signal "GND")
		(6 "In2.Cu" signal "IN1")
		(8 "In3.Cu" signal "GND1")
		(10 "In4.Cu" signal "IN2")
		(12 "In5.Cu" signal "GND2")
		(14 "In6.Cu" signal "IN3")
		(16 "In7.Cu" signal "GND3")
		(18 "In8.Cu" signal "VCC")
		(20 "In9.Cu" signal "VCC1")
		(22 "In10.Cu" signal "GND4")
		(24 "In11.Cu" signal "IN4")
		(26 "In12.Cu" signal "GND5")
		(28 "In13.Cu" signal "IN5")
		(30 "In14.Cu" signal "GND6")
		(32 "In15.Cu" signal "IN6")
		(34 "In16.Cu" signal "GND7")
		(2 "B.Cu" signal "BOTTOM")
		(9 "F.Adhes" user "F.Adhesive")
		(11 "B.Adhes" user "B.Adhesive")
		(13 "F.Paste" user "Package Geometry/Pastemask Top")
		(15 "B.Paste" user "Package Geometry/Pastemask Bottom")
		(5 "F.SilkS" user "Ref Des/Silkscreen Top")
		(7 "B.SilkS" user "Ref Des/Silkscreen Bottom")
		(1 "F.Mask" user "Board Geometry/Soldermask Top")
		(3 "B.Mask" user "Board Geometry/Soldermask Bottom")
		(17 "Dwgs.User" user "User.Drawings")
		(19 "Cmts.User" user "User.Comments")
		(21 "Eco1.User" user "User.Eco1")
		(23 "Eco2.User" user "User.Eco2")
		(25 "Edge.Cuts" user "Board Geometry/Outline")
		(27 "Margin" user)
		(31 "F.CrtYd" user "Package Geometry/Place Bound Top")
		(29 "B.CrtYd" user "Package Geometry/Place Bound Bottom")
		(35 "F.Fab" user "Ref Des/Assembly Top")
		(33 "B.Fab" user "Ref Des/Assembly Bottom")
	)
	(footprint ""
		(layer "F.Cu")
		(at 130.49758 -27.52598 90)
		(property "Reference" "R6190"
			(at 0 0 90)
			(layer "F.SilkS")
			(hide yes)
			(effects
				(font
					(size 1.27 1.27)
				)
			)
		)
		(property "Value" ""
			(at 0 0 90)
			(layer "F.Fab")
			(effects
				(font
					(size 1.27 1.27)
				)
			)
		)
		(duplicate_pad_numbers_are_jumpers no)
		(fp_line
			(start 0.32512 -0.175006)
			(end 0.32512 0.175006)
			(stroke
				(width 0.1)
				(type default)
			)
			(layer "F.Fab")
		)
		(fp_line
			(start -0.32512 -0.175006)
			(end 0.32512 -0.175006)
			(stroke
				(width 0.1)
				(type default)
			)
			(layer "F.Fab")
		)
		(fp_line
			(start 0.32512 0.175006)
			(end -0.32512 0.175006)
			(stroke
				(width 0.1)
				(type default)
			)
			(layer "F.Fab")
		)
		(fp_line
			(start -0.32512 0.175006)
			(end -0.32512 -0.175006)
			(stroke
				(width 0.1)
				(type default)
			)
			(layer "F.Fab")
		)
		(pad "1" smd rect
			(at -0.2667 0 90)
			(size 0.3048 0.381)
			(layers "F.Cu" "F.Mask" "F.Paste")
			(net "USB2_CPU0_P0_DP")
		)
		(pad "2" smd rect
			(at 0.2667 0 270)
			(size 0.3048 0.381)
			(layers "F.Cu" "F.Mask" "F.Paste")
			(net "USB2_CPU0_P0_R1_DP")
		)
	)
	(footprint ""
		(layer "F.Cu")
		(at 170.970702 -437.032146 90)
		(property "Reference" "R3433"
			(at 0 0 90)
			(layer "F.SilkS")
			(hide yes)
			(effects
				(font
					(size 1.27 1.27)
				)
			)
		)
		(property "Value" ""
			(at 0 0 90)
			(layer "F.Fab")
			(effects
				(font
					(size 1.27 1.27)
				)
			)
		)
		(duplicate_pad_numbers_are_jumpers no)
		(fp_line
			(start 0.7874 -0.4064)
			(end 0.7874 0.4064)
			(stroke
				(width 0.1524)
				(type default)
			)
			(layer "F.SilkS")
		)
		(fp_line
			(start -0.7874 -0.4064)
			(end 0.7874 -0.4064)
			(stroke
				(width 0.1524)
				(type default)
			)
			(layer "F.SilkS")
		)
		(fp_line
			(start 0.7874 0.4064)
			(end -0.7874 0.4064)
			(stroke
				(width 0.1524)
				(type default)
			)
			(layer "F.SilkS")
		)
		(fp_line
			(start -0.7874 0.4064)
			(end -0.7874 -0.4064)
			(stroke
				(width 0.1524)
				(type default)
			)
			(layer "F.SilkS")
		)
		(fp_line
			(start -0.12065 -0.305054)
			(end -0.12065 -0.2794)
			(stroke
				(width 0.1)
				(type default)
			)
			(layer "F.Fab")
		)
		(fp_line
			(start -0.67945 -0.305054)
			(end -0.12065 -0.305054)
			(stroke
				(width 0.1)
				(type default)
			)
			(layer "F.Fab")
		)
		(fp_line
			(start 0.67945 -0.3048)
			(end 0.67945 0.3048)
			(stroke
				(width 0.1)
				(type default)
			)
			(layer "F.Fab")
		)
		(fp_line
			(start 0.12065 -0.3048)
			(end 0.67945 -0.3048)
			(stroke
				(width 0.1)
				(type default)
			)
			(layer "F.Fab")
		)
		(fp_line
			(start 0.12065 -0.2794)
			(end 0.12065 -0.3048)
			(stroke
				(width 0.1)
				(type default)
			)
			(layer "F.Fab")
		)
		(fp_line
			(start -0.12065 -0.2794)
			(end 0.12065 -0.2794)
			(stroke
				(width 0.1)
				(type default)
			)
			(layer "F.Fab")
		)
		(fp_line
			(start 0.120396 0.2794)
			(end -0.12065 0.2794)
			(stroke
				(width 0.1)
				(type default)
			)
			(layer "F.Fab")
		)
		(fp_line
			(start -0.12065 0.2794)
			(end -0.12065 0.3048)
			(stroke
				(width 0.1)
				(type default)
			)
			(layer "F.Fab")
		)
		(fp_line
			(start 0.67945 0.3048)
			(end 0.120396 0.3048)
			(stroke
				(width 0.1)
				(type default)
			)
			(layer "F.Fab")
		)
		(fp_line
			(start 0.120396 0.3048)
			(end 0.120396 0.2794)
			(stroke
				(width 0.1)
				(type default)
			)
			(layer "F.Fab")
		)
		(fp_line
			(start -0.12065 0.3048)
			(end -0.67945 0.3048)
			(stroke
				(width 0.1)
				(type default)
			)
			(layer "F.Fab")
		)
		(fp_line
			(start -0.67945 0.3048)
			(end -0.67945 -0.305054)
			(stroke
				(width 0.1)
				(type default)
			)
			(layer "F.Fab")
		)
		(pad "1" smd circle
			(at -0.40005 0 90)
			(size 0 0)
			(layers "F.Cu" "F.Mask" "F.Paste")
			(net "P3V3_AUX")
		)
		(pad "2" smd circle
			(at 0.40005 0 90)
			(size 0 0)
			(layers "F.Cu" "F.Mask" "F.Paste")
			(net "GPU_BASE_HMC_READY_N")
		)
	)
	(footprint ""
		(layer "F.Cu")
		(at 328.506836 -150.589234 180)
		(property "Reference" "PR418"
			(at 0 0 180)
			(layer "F.SilkS")
			(hide yes)
			(effects
				(font
					(size 1.27 1.27)
				)
			)
		)
		(property "Value" ""
			(at 0 0 180)
			(layer "F.Fab")
			(effects
				(font
					(size 1.27 1.27)
				)
			)
		)
		(duplicate_pad_numbers_are_jumpers no)
		(fp_line
			(start 0.7874 0.4064)
			(end -0.7874 0.4064)
			(stroke
				(width 0.1524)
				(type default)
			)
			(layer "F.SilkS")
		)
		(fp_line
			(start 0.7874 -0.4064)
			(end 0.7874 0.4064)
			(stroke
				(width 0.1524)
				(type default)
			)
			(layer "F.SilkS")
		)
		(fp_line
			(start -0.7874 0.4064)
			(end -0.7874 -0.4064)
			(stroke
				(width 0.1524)
				(type default)
			)
			(layer "F.SilkS")
		)
		(fp_line
			(start -0.7874 -0.4064)
			(end 0.7874 -0.4064)
			(stroke
				(width 0.1524)
				(type default)
			)
			(layer "F.SilkS")
		)
		(fp_line
			(start 0.67945 0.3048)
			(end 0.120396 0.3048)
			(stroke
				(width 0.1)
				(type default)
			)
			(layer "F.Fab")
		)
		(fp_line
			(start 0.67945 -0.3048)
			(end 0.67945 0.3048)
			(stroke
				(width 0.1)
				(type default)
			)
			(layer "F.Fab")
		)
		(fp_line
			(start 0.12065 -0.2794)
			(end 0.12065 -0.3048)
			(stroke
				(width 0.1)
				(type default)
			)
			(layer "F.Fab")
		)
		(fp_line
			(start 0.12065 -0.3048)
			(end 0.67945 -0.3048)
			(stroke
				(width 0.1)
				(type default)
			)
			(layer "F.Fab")
		)
		(fp_line
			(start 0.120396 0.3048)
			(end 0.120396 0.2794)
			(stroke
				(width 0.1)
				(type default)
			)
			(layer "F.Fab")
		)
		(fp_line
			(start 0.120396 0.2794)
			(end -0.12065 0.2794)
			(stroke
				(width 0.1)
				(type default)
			)
			(layer "F.Fab")
		)
		(fp_line
			(start -0.12065 0.3048)
			(end -0.67945 0.3048)
			(stroke
				(width 0.1)
				(type default)
			)
			(layer "F.Fab")
		)
		(fp_line
			(start -0.12065 0.2794)
			(end -0.12065 0.3048)
			(stroke
				(width 0.1)
				(type default)
			)
			(layer "F.Fab")
		)
		(fp_line
			(start -0.12065 -0.2794)
			(end 0.12065 -0.2794)
			(stroke
				(width 0.1)
				(type default)
			)
			(layer "F.Fab")
		)
		(fp_line
			(start -0.12065 -0.305054)
			(end -0.12065 -0.2794)
			(stroke
				(width 0.1)
				(type default)
			)
			(layer "F.Fab")
		)
		(fp_line
			(start -0.67945 0.3048)
			(end -0.67945 -0.305054)
			(stroke
				(width 0.1)
				(type default)
			)
			(layer "F.Fab")
		)
		(fp_line
			(start -0.67945 -0.305054)
			(end -0.12065 -0.305054)
			(stroke
				(width 0.1)
				(type default)
			)
			(layer "F.Fab")
		)
		(pad "1" smd circle
			(at -0.40005 0 180)
			(size 0 0)
			(layers "F.Cu" "F.Mask" "F.Paste")
			(net "GND")
		)
		(pad "2" smd circle
			(at 0.40005 0 180)
			(size 0 0)
			(layers "F.Cu" "F.Mask" "F.Paste")
			(net "PVDD18_S5_P0_RGND")
		)
	)
)
